# S9S_MB_2U (Grand Teton) — schematic netlist excerpt (pin names and nets, part order shuffled) for the footprints in the layout excerpt that follows; sources: Cadence DE-HDL packaged netlist, KiCad conversion of 03242023_DA0F0TMBIJ0_F0T_Motherboard_J_brd_V01_OCP.brd

JP7  CONN3_210HP1030BR1  CONN3_210-HP1-030BR1 IO  pkg HEADER1X3XG  page 235
  \1\  = FM_SMB_PEHPCPU0_PCIE_ALERT_N
  \2\  = GND
  \3\  = FM_SMB_PEHPCPU1_PCIE_ALERT_N

R3127  Q_RES  10K 1% CHIP  pkg 0402LF  page 236 : A = P3V3_AUX ; B = PCA9543_S3M_INT1_N

(kicad_pcb
	(version 20260206)
	(generator "pcbnew")
	(generator_version "10.0")
	(general
		(thickness 1.6)
		(legacy_teardrops no)
	)
	(paper "A4")
	(title_block
		(title "03242023_DA0F0TMBIJ0_F0T_Motherboard_J_brd_V01_OCP.brd")
		(comment 1 "Grand Teton / footprints 219-220 of 6105")
	)
	(layers
		(0 "F.Cu" signal "TOP")
		(4 "In1.Cu" signal "GND")
		(6 "In2.Cu" signal "IN1")
		(8 "In3.Cu" signal "GND1")
		(10 "In4.Cu" signal "IN2")
		(12 "In5.Cu" signal "GND2")
		(14 "In6.Cu" signal "IN3")
		(16 "In7.Cu" signal "GND3")
		(18 "In8.Cu" signal "VCC")
		(20 "In9.Cu" signal "VCC1")
		(22 "In10.Cu" signal "GND4")
		(24 "In11.Cu" signal "IN4")
		(26 "In12.Cu" signal "GND5")
		(28 "In13.Cu" signal "IN5")
		(30 "In14.Cu" signal "GND6")
		(32 "In15.Cu" signal "IN6")
		(34 "In16.Cu" signal "GND7")
		(2 "B.Cu" signal "BOTTOM")
		(9 "F.Adhes" user "F.Adhesive")
		(11 "B.Adhes" user "B.Adhesive")
		(13 "F.Paste" user "Package Geometry/Pastemask Top")
		(15 "B.Paste" user "Package Geometry/Pastemask Bottom")
		(5 "F.SilkS" user "Ref Des/Silkscreen Top")
		(7 "B.SilkS" user "Ref Des/Silkscreen Bottom")
		(1 "F.Mask" user "Board Geometry/Soldermask Top")
		(3 "B.Mask" user "Board Geometry/Soldermask Bottom")
		(17 "Dwgs.User" user "User.Drawings")
		(19 "Cmts.User" user "User.Comments")
		(21 "Eco1.User" user "User.Eco1")
		(23 "Eco2.User" user "User.Eco2")
		(25 "Edge.Cuts" user "Board Geometry/Outline")
		(27 "Margin" user)
		(31 "F.CrtYd" user "Package Geometry/Place Bound Top")
		(29 "B.CrtYd" user "Package Geometry/Place Bound Bottom")
		(35 "F.Fab" user "Ref Des/Assembly Top")
		(33 "B.Fab" user "Ref Des/Assembly Bottom")
	)
	(footprint ""
		(layer "F.Cu")
		(at 162.34283 -77.862938 180)
		(property "Reference" "R3127"
			(at 0 0 180)
			(layer "F.SilkS")
			(hide yes)
			(effects
				(font
					(size 1.27 1.27)
				)
			)
		)
		(property "Value" ""
			(at 0 0 180)
			(layer "F.Fab")
			(effects
				(font
					(size 1.27 1.27)
				)
			)
		)
		(duplicate_pad_numbers_are_jumpers no)
		(fp_line
			(start 0.7874 0.4064)
			(end -0.7874 0.4064)
			(stroke
				(width 0.1524)
				(type default)
			)
			(layer "F.SilkS")
		)
		(fp_line
			(start 0.7874 -0.4064)
			(end 0.7874 0.4064)
			(stroke
				(width 0.1524)
				(type default)
			)
			(layer "F.SilkS")
		)
		(fp_line
			(start -0.7874 0.4064)
			(end -0.7874 -0.4064)
			(stroke
				(width 0.1524)
				(type default)
			)
			(layer "F.SilkS")
		)
		(fp_line
			(start -0.7874 -0.4064)
			(end 0.7874 -0.4064)
			(stroke
				(width 0.1524)
				(type default)
			)
			(layer "F.SilkS")
		)
		(fp_line
			(start 0.67945 0.3048)
			(end 0.120396 0.3048)
			(stroke
				(width 0.1)
				(type default)
			)
			(layer "F.Fab")
		)
		(fp_line
			(start 0.67945 -0.3048)
			(end 0.67945 0.3048)
			(stroke
				(width 0.1)
				(type default)
			)
			(layer "F.Fab")
		)
		(fp_line
			(start 0.12065 -0.2794)
			(end 0.12065 -0.3048)
			(stroke
				(width 0.1)
				(type default)
			)
			(layer "F.Fab")
		)
		(fp_line
			(start 0.12065 -0.3048)
			(end 0.67945 -0.3048)
			(stroke
				(width 0.1)
				(type default)
			)
			(layer "F.Fab")
		)
		(fp_line
			(start 0.120396 0.3048)
			(end 0.120396 0.2794)
			(stroke
				(width 0.1)
				(type default)
			)
			(layer "F.Fab")
		)
		(fp_line
			(start 0.120396 0.2794)
			(end -0.12065 0.2794)
			(stroke
				(width 0.1)
				(type default)
			)
			(layer "F.Fab")
		)
		(fp_line
			(start -0.12065 0.3048)
			(end -0.67945 0.3048)
			(stroke
				(width 0.1)
				(type default)
			)
			(layer "F.Fab")
		)
		(fp_line
			(start -0.12065 0.2794)
			(end -0.12065 0.3048)
			(stroke
				(width 0.1)
				(type default)
			)
			(layer "F.Fab")
		)
		(fp_line
			(start -0.12065 -0.2794)
			(end 0.12065 -0.2794)
			(stroke
				(width 0.1)
				(type default)
			)
			(layer "F.Fab")
		)
		(fp_line
			(start -0.12065 -0.305054)
			(end -0.12065 -0.2794)
			(stroke
				(width 0.1)
				(type default)
			)
			(layer "F.Fab")
		)
		(fp_line
			(start -0.67945 0.3048)
			(end -0.67945 -0.305054)
			(stroke
				(width 0.1)
				(type default)
			)
			(layer "F.Fab")
		)
		(fp_line
			(start -0.67945 -0.305054)
			(end -0.12065 -0.305054)
			(stroke
				(width 0.1)
				(type default)
			)
			(layer "F.Fab")
		)
		(pad "1" smd circle
			(at -0.40005 0 180)
			(size 0 0)
			(layers "F.Cu" "F.Mask" "F.Paste")
			(net "P3V3_AUX")
		)
		(pad "2" smd circle
			(at 0.40005 0 180)
			(size 0 0)
			(layers "F.Cu" "F.Mask" "F.Paste")
			(net "PCA9543_S3M_INT1_N")
		)
	)
	(footprint ""
		(layer "F.Cu")
		(at 449.950078 -412.660084 180)
		(property "Reference" "JP7"
			(at 1.034796 -2.340356 0)
			(unlocked yes)
			(layer "F.SilkS")
			(effects
				(font
					(size 0.7874 0.5842)
					(thickness 0.1524)
				)
				(justify left)
			)
		)
		(property "Value" ""
			(at 0 0 180)
			(layer "F.Fab")
			(effects
				(font
					(size 1.27 1.27)
				)
			)
		)
		(duplicate_pad_numbers_are_jumpers no)
		(fp_line
			(start 1.249934 6.400038)
			(end -1.249934 6.400038)
			(stroke
				(width 0.1524)
				(type default)
			)
			(layer "F.SilkS")
		)
		(fp_line
			(start 1.249934 -1.320038)
			(end 1.249934 6.400038)
			(stroke
				(width 0.1524)
				(type default)
			)
			(layer "F.SilkS")
		)
		(fp_line
			(start -1.249934 6.400038)
			(end -1.249934 -1.320038)
			(stroke
				(width 0.1524)
				(type default)
			)
			(layer "F.SilkS")
		)
		(fp_line
			(start -1.249934 -1.320038)
			(end 1.249934 -1.320038)
			(stroke
				(width 0.1524)
				(type default)
			)
			(layer "F.SilkS")
		)
		(fp_poly
			(pts
				(xy -1.452372 0) (xy -2.5654 0.556514) (xy -2.5654 -0.556514)
			)
			(stroke
				(width 0)
				(type default)
			)
			(fill yes)
			(layer "F.SilkS")
		)
		(fp_line
			(start 1.249934 6.400038)
			(end -1.249934 6.400038)
			(stroke
				(width 0.1)
				(type default)
			)
			(layer "F.Fab")
		)
		(fp_line
			(start 1.249934 -1.320038)
			(end 1.249934 6.400038)
			(stroke
				(width 0.1)
				(type default)
			)
			(layer "F.Fab")
		)
		(fp_line
			(start -1.249934 6.400038)
			(end -1.249934 -1.320038)
			(stroke
				(width 0.1)
				(type default)
			)
			(layer "F.Fab")
		)
		(fp_line
			(start -1.249934 -1.320038)
			(end 1.249934 -1.320038)
			(stroke
				(width 0.1)
				(type default)
			)
			(layer "F.Fab")
		)
		(fp_poly
			(pts
				(xy -2.5654 -0.556514) (xy -1.452372 0) (xy -2.5654 0.556514)
			)
			(stroke
				(width 0)
				(type default)
			)
			(fill yes)
			(layer "F.Fab")
		)
		(fp_text user "3"
			(at -1.804162 5.177028 0)
			(unlocked yes)
			(layer "F.SilkS")
			(effects
				(font
					(size 0.7874 0.5842)
					(thickness 0.1524)
				)
			)
		)
		(fp_text user "1"
			(at -1.346962 -0.136652 0)
			(unlocked yes)
			(layer "B.SilkS")
			(effects
				(font
					(size 0.7874 0.5842)
					(thickness 0.1524)
				)
				(justify mirror)
			)
		)
		(fp_text user "3"
			(at -1.575562 5.255768 0)
			(unlocked yes)
			(layer "B.SilkS")
			(effects
				(font
					(size 0.7874 0.5842)
					(thickness 0.1524)
				)
				(justify mirror)
			)
		)
		(fp_text user "1"
			(at -1.143 0.02667 180)
			(unlocked yes)
			(layer "B.Fab")
			(effects
				(font
					(size 0.7874 0.5842)
					(thickness 0.1524)
				)
				(justify mirror)
			)
		)
		(fp_text user "3"
			(at -1.1557 5.18287 180)
			(unlocked yes)
			(layer "B.Fab")
			(effects
				(font
					(size 0.7874 0.5842)
					(thickness 0.1524)
				)
				(justify mirror)
			)
		)
		(fp_text user "3"
			(at -1.778 5.13207 180)
			(unlocked yes)
			(layer "F.Fab")
			(effects
				(font
					(size 0.7874 0.5842)
					(thickness 0.1524)
				)
			)
		)
		(pad "1" thru_hole rect
			(at 0 0 180)
			(size 1.5494 1.5494)
			(drill 1.0414)
			(layers "*.Cu" "*.Mask")
			(remove_unused_layers no)
			(net "FM_SMB_PEHPCPU0_PCIE_ALERT_N")
			(clearance 0)
			(padstack
				(mode front_inner_back)
				(layer "Inner"
					(shape circle)
					(size 1.5494 1.5494)
					(clearance 0)
				)
				(layer "B.Cu"
					(shape rect)
					(size 1.5494 1.5494)
					(clearance 0)
				)
			)
		)
		(pad "2" thru_hole circle
			(at 0 2.54 180)
			(size 1.5494 1.5494)
			(drill 1.0414)
			(layers "*.Cu" "*.Mask")
			(remove_unused_layers no)
			(net "GND")
			(clearance 0)
		)
		(pad "3" thru_hole circle
			(at 0 5.08 180)
			(size 1.5494 1.5494)
			(drill 1.0414)
			(layers "*.Cu" "*.Mask")
			(remove_unused_layers no)
			(net "FM_SMB_PEHPCPU1_PCIE_ALERT_N")
			(clearance 0)
		)
	)
)
